# T6G (Grand Teton) — schematic netlist excerpt (pin names and nets, part order shuffled) for the footprints in the layout excerpt that follows; sources: Cadence DE-HDL packaged netlist, KiCad conversion of 04192023_DAF0TMB3IC0_F0TG_MB_C_brd_V02_OCP.brd

PC225_2  Q_CAP  22UF 4V 20% X6S  pkg C0805  page 208 : A = PVDD11_S3_P0 ; B = GND
R3226  Q_RES  2.2K 5% EMPTY  pkg 0402LF  page 151 : A = SMB_1_BMC_GPU_SCL ; B = P3V3_AUX
R1696  Q_RES  10 1% CHIP  pkg 0402LF  page 99 : A = I3C_SPD_DDRAF_CPU1_SDA ; B = I3C_SPD_DDRB_CPU1_SDA

(kicad_pcb
	(version 20260206)
	(generator "pcbnew")
	(generator_version "10.0")
	(general
		(thickness 1.6)
		(legacy_teardrops no)
	)
	(paper "A4")
	(title_block
		(title "04192023_DAF0TMB3IC0_F0TG_MB_C_brd_V02_OCP.brd")
		(comment 1 "Grand Teton / footprints 5896-5898 of 8354")
	)
	(layers
		(0 "F.Cu" signal "TOP")
		(4 "In1.Cu" signal "GND")
		(6 "In2.Cu" signal "IN1")
		(8 "In3.Cu" signal "GND1")
		(10 "In4.Cu" signal "IN2")
		(12 "In5.Cu" signal "GND2")
		(14 "In6.Cu" signal "IN3")
		(16 "In7.Cu" signal "GND3")
		(18 "In8.Cu" signal "VCC")
		(20 "In9.Cu" signal "VCC1")
		(22 "In10.Cu" signal "GND4")
		(24 "In11.Cu" signal "IN4")
		(26 "In12.Cu" signal "GND5")
		(28 "In13.Cu" signal "IN5")
		(30 "In14.Cu" signal "GND6")
		(32 "In15.Cu" signal "IN6")
		(34 "In16.Cu" signal "GND7")
		(2 "B.Cu" signal "BOTTOM")
		(9 "F.Adhes" user "F.Adhesive")
		(11 "B.Adhes" user "B.Adhesive")
		(13 "F.Paste" user "Package Geometry/Pastemask Top")
		(15 "B.Paste" user "Package Geometry/Pastemask Bottom")
		(5 "F.SilkS" user "Ref Des/Silkscreen Top")
		(7 "B.SilkS" user "Ref Des/Silkscreen Bottom")
		(1 "F.Mask" user "Board Geometry/Soldermask Top")
		(3 "B.Mask" user "Board Geometry/Soldermask Bottom")
		(17 "Dwgs.User" user "User.Drawings")
		(19 "Cmts.User" user "User.Comments")
		(21 "Eco1.User" user "User.Eco1")
		(23 "Eco2.User" user "User.Eco2")
		(25 "Edge.Cuts" user "Board Geometry/Outline")
		(27 "Margin" user)
		(31 "F.CrtYd" user "Package Geometry/Place Bound Top")
		(29 "B.CrtYd" user "Package Geometry/Place Bound Bottom")
		(35 "F.Fab" user "Ref Des/Assembly Top")
		(33 "B.Fab" user "Ref Des/Assembly Bottom")
	)
	(footprint ""
		(layer "B.Cu")
		(at 153.990802 -16.851122 -90)
		(property "Reference" "R3226"
			(at 0 0 90)
			(layer "B.SilkS")
			(hide yes)
			(effects
				(font
					(size 1.27 1.27)
				)
				(justify mirror)
			)
		)
		(property "Value" ""
			(at 0 0 90)
			(layer "B.Fab")
			(effects
				(font
					(size 1.27 1.27)
				)
				(justify mirror)
			)
		)
		(duplicate_pad_numbers_are_jumpers no)
		(fp_line
			(start -0.7874 0.4064)
			(end 0.7874 0.4064)
			(stroke
				(width 0.1524)
				(type default)
			)
			(layer "B.SilkS")
		)
		(fp_line
			(start 0.7874 0.4064)
			(end 0.7874 -0.4064)
			(stroke
				(width 0.1524)
				(type default)
			)
			(layer "B.SilkS")
		)
		(fp_line
			(start -0.7874 -0.4064)
			(end -0.7874 0.4064)
			(stroke
				(width 0.1524)
				(type default)
			)
			(layer "B.SilkS")
		)
		(fp_line
			(start 0.7874 -0.4064)
			(end -0.7874 -0.4064)
			(stroke
				(width 0.1524)
				(type default)
			)
			(layer "B.SilkS")
		)
		(fp_line
			(start -0.67945 0.3048)
			(end -0.120396 0.3048)
			(stroke
				(width 0.1)
				(type default)
			)
			(layer "B.Fab")
		)
		(fp_line
			(start -0.120396 0.3048)
			(end -0.120396 0.2794)
			(stroke
				(width 0.1)
				(type default)
			)
			(layer "B.Fab")
		)
		(fp_line
			(start 0.12065 0.3048)
			(end 0.67945 0.3048)
			(stroke
				(width 0.1)
				(type default)
			)
			(layer "B.Fab")
		)
		(fp_line
			(start 0.67945 0.3048)
			(end 0.67945 -0.305054)
			(stroke
				(width 0.1)
				(type default)
			)
			(layer "B.Fab")
		)
		(fp_line
			(start -0.120396 0.2794)
			(end 0.12065 0.2794)
			(stroke
				(width 0.1)
				(type default)
			)
			(layer "B.Fab")
		)
		(fp_line
			(start 0.12065 0.2794)
			(end 0.12065 0.3048)
			(stroke
				(width 0.1)
				(type default)
			)
			(layer "B.Fab")
		)
		(fp_line
			(start -0.12065 -0.2794)
			(end -0.12065 -0.3048)
			(stroke
				(width 0.1)
				(type default)
			)
			(layer "B.Fab")
		)
		(fp_line
			(start 0.12065 -0.2794)
			(end -0.12065 -0.2794)
			(stroke
				(width 0.1)
				(type default)
			)
			(layer "B.Fab")
		)
		(fp_line
			(start -0.67945 -0.3048)
			(end -0.67945 0.3048)
			(stroke
				(width 0.1)
				(type default)
			)
			(layer "B.Fab")
		)
		(fp_line
			(start -0.12065 -0.3048)
			(end -0.67945 -0.3048)
			(stroke
				(width 0.1)
				(type default)
			)
			(layer "B.Fab")
		)
		(fp_line
			(start 0.12065 -0.305054)
			(end 0.12065 -0.2794)
			(stroke
				(width 0.1)
				(type default)
			)
			(layer "B.Fab")
		)
		(fp_line
			(start 0.67945 -0.305054)
			(end 0.12065 -0.305054)
			(stroke
				(width 0.1)
				(type default)
			)
			(layer "B.Fab")
		)
		(pad "1" smd circle
			(at 0.40005 0 90)
			(size 0 0)
			(layers "B.Cu" "B.Mask" "B.Paste")
			(net "SMB_1_BMC_GPU_SCL")
		)
		(pad "2" smd circle
			(at -0.40005 0 90)
			(size 0 0)
			(layers "B.Cu" "B.Mask" "B.Paste")
			(net "P3V3_AUX")
		)
	)
	(footprint ""
		(layer "B.Cu")
		(at 51.120548 -195.926964 180)
		(property "Reference" "R1696"
			(at 0 0 0)
			(layer "B.SilkS")
			(hide yes)
			(effects
				(font
					(size 1.27 1.27)
				)
				(justify mirror)
			)
		)
		(property "Value" ""
			(at 0 0 0)
			(layer "B.Fab")
			(effects
				(font
					(size 1.27 1.27)
				)
				(justify mirror)
			)
		)
		(duplicate_pad_numbers_are_jumpers no)
		(fp_line
			(start 0.7874 0.4064)
			(end 0.7874 -0.4064)
			(stroke
				(width 0.1524)
				(type default)
			)
			(layer "B.SilkS")
		)
		(fp_line
			(start 0.7874 -0.4064)
			(end -0.7874 -0.4064)
			(stroke
				(width 0.1524)
				(type default)
			)
			(layer "B.SilkS")
		)
		(fp_line
			(start -0.7874 0.4064)
			(end 0.7874 0.4064)
			(stroke
				(width 0.1524)
				(type default)
			)
			(layer "B.SilkS")
		)
		(fp_line
			(start -0.7874 -0.4064)
			(end -0.7874 0.4064)
			(stroke
				(width 0.1524)
				(type default)
			)
			(layer "B.SilkS")
		)
		(fp_line
			(start 0.67945 0.3048)
			(end 0.67945 -0.305054)
			(stroke
				(width 0.1)
				(type default)
			)
			(layer "B.Fab")
		)
		(fp_line
			(start 0.67945 -0.305054)
			(end 0.12065 -0.305054)
			(stroke
				(width 0.1)
				(type default)
			)
			(layer "B.Fab")
		)
		(fp_line
			(start 0.12065 0.3048)
			(end 0.67945 0.3048)
			(stroke
				(width 0.1)
				(type default)
			)
			(layer "B.Fab")
		)
		(fp_line
			(start 0.12065 0.2794)
			(end 0.12065 0.3048)
			(stroke
				(width 0.1)
				(type default)
			)
			(layer "B.Fab")
		)
		(fp_line
			(start 0.12065 -0.2794)
			(end -0.12065 -0.2794)
			(stroke
				(width 0.1)
				(type default)
			)
			(layer "B.Fab")
		)
		(fp_line
			(start 0.12065 -0.305054)
			(end 0.12065 -0.2794)
			(stroke
				(width 0.1)
				(type default)
			)
			(layer "B.Fab")
		)
		(fp_line
			(start -0.120396 0.3048)
			(end -0.120396 0.2794)
			(stroke
				(width 0.1)
				(type default)
			)
			(layer "B.Fab")
		)
		(fp_line
			(start -0.120396 0.2794)
			(end 0.12065 0.2794)
			(stroke
				(width 0.1)
				(type default)
			)
			(layer "B.Fab")
		)
		(fp_line
			(start -0.12065 -0.2794)
			(end -0.12065 -0.3048)
			(stroke
				(width 0.1)
				(type default)
			)
			(layer "B.Fab")
		)
		(fp_line
			(start -0.12065 -0.3048)
			(end -0.67945 -0.3048)
			(stroke
				(width 0.1)
				(type default)
			)
			(layer "B.Fab")
		)
		(fp_line
			(start -0.67945 0.3048)
			(end -0.120396 0.3048)
			(stroke
				(width 0.1)
				(type default)
			)
			(layer "B.Fab")
		)
		(fp_line
			(start -0.67945 -0.3048)
			(end -0.67945 0.3048)
			(stroke
				(width 0.1)
				(type default)
			)
			(layer "B.Fab")
		)
		(pad "1" smd circle
			(at 0.40005 0)
			(size 0 0)
			(layers "B.Cu" "B.Mask" "B.Paste")
			(net "I3C_SPD_DDRAF_CPU1_SDA")
		)
		(pad "2" smd circle
			(at -0.40005 0)
			(size 0 0)
			(layers "B.Cu" "B.Mask" "B.Paste")
			(net "I3C_SPD_DDRB_CPU1_SDA")
		)
	)
	(footprint ""
		(layer "B.Cu")
		(at 418.128958 -342.007952 -90)
		(property "Reference" "PC225_2"
			(at 0 0 90)
			(layer "B.SilkS")
			(hide yes)
			(effects
				(font
					(size 1.27 1.27)
				)
				(justify mirror)
			)
		)
		(property "Value" ""
			(at 0 0 90)
			(layer "B.Fab")
			(effects
				(font
					(size 1.27 1.27)
				)
				(justify mirror)
			)
		)
		(duplicate_pad_numbers_are_jumpers no)
		(fp_line
			(start -1.524 0.762)
			(end 1.524 0.762)
			(stroke
				(width 0.1524)
				(type default)
			)
			(layer "B.SilkS")
		)
		(fp_line
			(start 1.524 0.762)
			(end 1.524 -0.762)
			(stroke
				(width 0.1524)
				(type default)
			)
			(layer "B.SilkS")
		)
		(fp_line
			(start -1.524 -0.762)
			(end -1.524 0.762)
			(stroke
				(width 0.1524)
				(type default)
			)
			(layer "B.SilkS")
		)
		(fp_line
			(start 1.524 -0.762)
			(end -1.524 -0.762)
			(stroke
				(width 0.1524)
				(type default)
			)
			(layer "B.SilkS")
		)
		(fp_line
			(start -1.1049 0.724916)
			(end -1.1049 -0.724916)
			(stroke
				(width 0.1)
				(type default)
			)
			(layer "B.Fab")
		)
		(fp_line
			(start 1.1049 0.724916)
			(end -1.1049 0.724916)
			(stroke
				(width 0.1)
				(type default)
			)
			(layer "B.Fab")
		)
		(fp_line
			(start -1.1049 -0.724916)
			(end 1.1049 -0.724916)
			(stroke
				(width 0.1)
				(type default)
			)
			(layer "B.Fab")
		)
		(fp_line
			(start 1.1049 -0.724916)
			(end 1.1049 0.724916)
			(stroke
				(width 0.1)
				(type default)
			)
			(layer "B.Fab")
		)
		(pad "1" smd rect
			(at 0.889 0 270)
			(size 1.016 1.27)
			(layers "B.Cu" "B.Mask" "B.Paste")
			(net "PVDD11_S3_P0")
		)
		(pad "2" smd rect
			(at -0.889 0 270)
			(size 1.016 1.27)
			(layers "B.Cu" "B.Mask" "B.Paste")
			(net "GND")
		)
	)
)
